FILE_TYPE = CONNECTIVITY;
{Allegro Design Entry HDL 16.6-p007 (v16-6-112F) 10/10/2012}
"PAGE_NUMBER" = 34;
0"NC";
1"UPI_CPU0_CPU1_P1P1_DN<19..0>";
2"UPI_CPU0_CPU1_P1P1_DP<19..0>";
3"UPI_CPU1_CPU0_P1P1_DN<19..0>";
4"UPI_CPU1_CPU0_P1P1_DP<19..0>";
5"UPI_CPU1_CPU0_P1P1_DP<13>";
6"UPI_CPU1_CPU0_P1P1_DP<11>";
7"UPI_CPU0_CPU1_P1P1_DP<11>";
8"UPI_CPU0_CPU1_P1P1_DP<9>";
9"UPI_CPU0_CPU1_P1P1_DP<12>";
10"UPI_CPU0_CPU1_P1P1_DN<9>";
11"UPI_CPU0_CPU1_P1P1_DN<6>";
12"UPI_CPU0_CPU1_P1P1_DN<4>";
13"UPI_CPU0_CPU1_P1P1_DP<3>";
14"UPI_CPU1_CPU0_P1P1_DP<12>";
15"UPI_CPU1_CPU0_P1P1_DN<19>";
16"UPI_CPU1_CPU0_P1P1_DN<18>";
17"UPI_CPU1_CPU0_P1P1_DN<17>";
18"UPI_CPU1_CPU0_P1P1_DN<16>";
19"UPI_CPU1_CPU0_P1P1_DN<15>";
20"UPI_CPU1_CPU0_P1P1_DN<14>";
21"UPI_CPU1_CPU0_P1P1_DN<13>";
22"UPI_CPU1_CPU0_P1P1_DN<12>";
23"UPI_CPU1_CPU0_P1P1_DN<11>";
24"UPI_CPU1_CPU0_P1P1_DN<10>";
25"UPI_CPU1_CPU0_P1P1_DP<19>";
26"UPI_CPU1_CPU0_P1P1_DP<18>";
27"UPI_CPU1_CPU0_P1P1_DP<17>";
28"UPI_CPU1_CPU0_P1P1_DP<16>";
29"UPI_CPU1_CPU0_P1P1_DP<15>";
30"UPI_CPU1_CPU0_P1P1_DP<14>";
31"UPI_CPU1_CPU0_P1P1_DP<10>";
32"UPI_CPU1_CPU0_P1P1_DP<9>";
33"UPI_CPU1_CPU0_P1P1_DP<8>";
34"UPI_CPU1_CPU0_P1P1_DP<7>";
35"UPI_CPU1_CPU0_P1P1_DP<6>";
36"UPI_CPU1_CPU0_P1P1_DP<5>";
37"UPI_CPU1_CPU0_P1P1_DP<4>";
38"UPI_CPU1_CPU0_P1P1_DP<3>";
39"UPI_CPU1_CPU0_P1P1_DP<2>";
40"UPI_CPU1_CPU0_P1P1_DP<1>";
41"UPI_CPU1_CPU0_P1P1_DP<0>";
42"UPI_CPU1_CPU0_P1P1_DN<9>";
43"UPI_CPU1_CPU0_P1P1_DN<8>";
44"UPI_CPU1_CPU0_P1P1_DN<7>";
45"UPI_CPU1_CPU0_P1P1_DN<6>";
46"UPI_CPU1_CPU0_P1P1_DN<5>";
47"UPI_CPU1_CPU0_P1P1_DN<4>";
48"UPI_CPU1_CPU0_P1P1_DN<3>";
49"UPI_CPU1_CPU0_P1P1_DN<2>";
50"UPI_CPU1_CPU0_P1P1_DN<1>";
51"UPI_CPU1_CPU0_P1P1_DN<0>";
52"UPI_CPU0_CPU1_P1P1_DN<19>";
53"UPI_CPU0_CPU1_P1P1_DN<18>";
54"UPI_CPU0_CPU1_P1P1_DN<17>";
55"UPI_CPU0_CPU1_P1P1_DN<16>";
56"UPI_CPU0_CPU1_P1P1_DN<15>";
57"UPI_CPU0_CPU1_P1P1_DN<14>";
58"UPI_CPU0_CPU1_P1P1_DN<13>";
59"UPI_CPU0_CPU1_P1P1_DN<12>";
60"UPI_CPU0_CPU1_P1P1_DN<11>";
61"UPI_CPU0_CPU1_P1P1_DN<10>";
62"UPI_CPU0_CPU1_P1P1_DP<19>";
63"UPI_CPU0_CPU1_P1P1_DP<18>";
64"UPI_CPU0_CPU1_P1P1_DP<17>";
65"UPI_CPU0_CPU1_P1P1_DP<16>";
66"UPI_CPU0_CPU1_P1P1_DP<15>";
67"UPI_CPU0_CPU1_P1P1_DP<14>";
68"UPI_CPU0_CPU1_P1P1_DP<13>";
69"UPI_CPU0_CPU1_P1P1_DP<10>";
70"UPI_CPU0_CPU1_P1P1_DP<8>";
71"UPI_CPU0_CPU1_P1P1_DP<7>";
72"UPI_CPU0_CPU1_P1P1_DP<6>";
73"UPI_CPU0_CPU1_P1P1_DP<5>";
74"UPI_CPU0_CPU1_P1P1_DP<4>";
75"UPI_CPU0_CPU1_P1P1_DP<2>";
76"UPI_CPU0_CPU1_P1P1_DP<1>";
77"UPI_CPU0_CPU1_P1P1_DP<0>";
78"UPI_CPU0_CPU1_P1P1_DN<8>";
79"UPI_CPU0_CPU1_P1P1_DN<7>";
80"UPI_CPU0_CPU1_P1P1_DN<5>";
81"UPI_CPU0_CPU1_P1P1_DN<3>";
82"UPI_CPU0_CPU1_P1P1_DN<2>";
83"UPI_CPU0_CPU1_P1P1_DN<1>";
84"UPI_CPU0_CPU1_P1P1_DN<0>";
%"TAP"
"1","(-5300,1925)","2","mstr_standard","I10";
;
CDS_LIB"mstr_standard"
BODY_TYPE"PLUMBING"
HDL_TAP"TRUE";
"B \NAC \NWC"3;
"S \NAC"
BN"12"22;
%"TAP"
"1","(-5300,1825)","2","mstr_standard","I11";
;
CDS_LIB"mstr_standard"
BODY_TYPE"PLUMBING"
HDL_TAP"TRUE";
"B \NAC \NWC"3;
"S \NAC"
BN"14"20;
%"TAP"
"1","(-5300,1975)","2","mstr_standard","I12";
;
CDS_LIB"mstr_standard"
BODY_TYPE"PLUMBING"
HDL_TAP"TRUE";
"B \NAC \NWC"3;
"S \NAC"
BN"11"23;
%"TAP"
"1","(-5300,2025)","2","mstr_standard","I13";
;
CDS_LIB"mstr_standard"
BODY_TYPE"PLUMBING"
HDL_TAP"TRUE";
"B \NAC \NWC"3;
"S \NAC"
BN"10"24;
%"TAP"
"1","(-5300,2075)","2","mstr_standard","I14";
;
CDS_LIB"mstr_standard"
BODY_TYPE"PLUMBING"
HDL_TAP"TRUE";
"B \NAC \NWC"3;
"S \NAC"
BN"9"42;
%"TAP"
"1","(-5300,2125)","2","mstr_standard","I15";
;
CDS_LIB"mstr_standard"
BODY_TYPE"PLUMBING"
HDL_TAP"TRUE";
"B \NAC \NWC"3;
"S \NAC"
BN"8"43;
%"TAP"
"1","(-5300,2175)","2","mstr_standard","I16";
;
CDS_LIB"mstr_standard"
BODY_TYPE"PLUMBING"
HDL_TAP"TRUE";
"B \NAC \NWC"3;
"S \NAC"
BN"7"44;
%"TAP"
"1","(-5300,2225)","2","mstr_standard","I17";
;
CDS_LIB"mstr_standard"
BODY_TYPE"PLUMBING"
HDL_TAP"TRUE";
"B \NAC \NWC"3;
"S \NAC"
BN"6"45;
%"TAP"
"1","(-5300,2275)","2","mstr_standard","I18";
;
CDS_LIB"mstr_standard"
BODY_TYPE"PLUMBING"
HDL_TAP"TRUE";
"B \NAC \NWC"3;
"S \NAC"
BN"5"46;
%"TAP"
"1","(-5300,2325)","2","mstr_standard","I19";
;
CDS_LIB"mstr_standard"
BODY_TYPE"PLUMBING"
HDL_TAP"TRUE";
"B \NAC \NWC"3;
"S \NAC"
BN"4"47;
%"TAP"
"1","(-5300,2375)","2","mstr_standard","I20";
;
CDS_LIB"mstr_standard"
BODY_TYPE"PLUMBING"
HDL_TAP"TRUE";
"B \NAC \NWC"3;
"S \NAC"
BN"3"48;
%"TAP"
"1","(-5300,2425)","2","mstr_standard","I21";
;
CDS_LIB"mstr_standard"
BODY_TYPE"PLUMBING"
HDL_TAP"TRUE";
"B \NAC \NWC"3;
"S \NAC"
BN"2"49;
%"TAP"
"1","(-5300,2475)","2","mstr_standard","I22";
;
CDS_LIB"mstr_standard"
BODY_TYPE"PLUMBING"
HDL_TAP"TRUE";
"B \NAC \NWC"3;
"S \NAC"
BN"1"50;
%"TAP"
"1","(-5300,2525)","2","mstr_standard","I23";
;
CDS_LIB"mstr_standard"
BODY_TYPE"PLUMBING"
HDL_TAP"TRUE";
"B \NAC \NWC"3;
"S \NAC"
BN"0"51;
%"TAP"
"1","(-5300,2625)","2","mstr_standard","I24";
;
CDS_LIB"mstr_standard"
BODY_TYPE"PLUMBING"
HDL_TAP"TRUE";
"B \NAC \NWC"4;
"S \NAC"
BN"19"25;
%"TAP"
"1","(-5300,2775)","2","mstr_standard","I25";
;
CDS_LIB"mstr_standard"
BODY_TYPE"PLUMBING"
HDL_TAP"TRUE";
"B \NAC \NWC"4;
"S \NAC"
BN"16"28;
%"TAP"
"1","(-5300,2725)","2","mstr_standard","I26";
;
CDS_LIB"mstr_standard"
BODY_TYPE"PLUMBING"
HDL_TAP"TRUE";
"B \NAC \NWC"4;
"S \NAC"
BN"17"27;
%"TAP"
"1","(-5300,2675)","2","mstr_standard","I27";
;
CDS_LIB"mstr_standard"
BODY_TYPE"PLUMBING"
HDL_TAP"TRUE";
"B \NAC \NWC"4;
"S \NAC"
BN"18"26;
%"TAP"
"1","(-5300,2825)","2","mstr_standard","I28";
;
CDS_LIB"mstr_standard"
BODY_TYPE"PLUMBING"
HDL_TAP"TRUE";
"B \NAC \NWC"4;
"S \NAC"
BN"15"29;
%"TAP"
"1","(-5300,2875)","2","mstr_standard","I29";
;
CDS_LIB"mstr_standard"
BODY_TYPE"PLUMBING"
HDL_TAP"TRUE";
"B \NAC \NWC"4;
"S \NAC"
BN"14"30;
%"TAP"
"1","(-5300,1625)","2","mstr_standard","I3";
;
CDS_LIB"mstr_standard"
BODY_TYPE"PLUMBING"
HDL_TAP"TRUE";
"B \NAC \NWC"3;
"S \NAC"
BN"18"16;
%"TAP"
"1","(-5300,2925)","2","mstr_standard","I30";
;
CDS_LIB"mstr_standard"
BODY_TYPE"PLUMBING"
HDL_TAP"TRUE";
"B \NAC \NWC"4;
"S \NAC"
BN"13"5;
%"TAP"
"1","(-5300,2975)","2","mstr_standard","I31";
;
CDS_LIB"mstr_standard"
BODY_TYPE"PLUMBING"
HDL_TAP"TRUE";
"B \NAC \NWC"4;
"S \NAC"
BN"12"14;
%"TAP"
"1","(-5300,3075)","2","mstr_standard","I32";
;
CDS_LIB"mstr_standard"
BODY_TYPE"PLUMBING"
HDL_TAP"TRUE";
"B \NAC \NWC"4;
"S \NAC"
BN"10"31;
%"TAP"
"1","(-5300,3025)","2","mstr_standard","I33";
;
CDS_LIB"mstr_standard"
BODY_TYPE"PLUMBING"
HDL_TAP"TRUE";
"B \NAC \NWC"4;
"S \NAC"
BN"11"6;
%"TAP"
"1","(-5300,3125)","2","mstr_standard","I34";
;
CDS_LIB"mstr_standard"
BODY_TYPE"PLUMBING"
HDL_TAP"TRUE";
"B \NAC \NWC"4;
"S \NAC"
BN"9"32;
%"TAP"
"1","(-5300,3175)","2","mstr_standard","I35";
;
CDS_LIB"mstr_standard"
BODY_TYPE"PLUMBING"
HDL_TAP"TRUE";
"B \NAC \NWC"4;
"S \NAC"
BN"8"33;
%"TAP"
"1","(-5300,3225)","2","mstr_standard","I36";
;
CDS_LIB"mstr_standard"
BODY_TYPE"PLUMBING"
HDL_TAP"TRUE";
"B \NAC \NWC"4;
"S \NAC"
BN"7"34;
%"TAP"
"1","(-5300,3325)","2","mstr_standard","I37";
;
CDS_LIB"mstr_standard"
BODY_TYPE"PLUMBING"
HDL_TAP"TRUE";
"B \NAC \NWC"4;
"S \NAC"
BN"5"36;
%"TAP"
"1","(-5300,3275)","2","mstr_standard","I38";
;
CDS_LIB"mstr_standard"
BODY_TYPE"PLUMBING"
HDL_TAP"TRUE";
"B \NAC \NWC"4;
"S \NAC"
BN"6"35;
%"TAP"
"1","(-5300,3375)","2","mstr_standard","I39";
;
CDS_LIB"mstr_standard"
BODY_TYPE"PLUMBING"
HDL_TAP"TRUE";
"B \NAC \NWC"4;
"S \NAC"
BN"4"37;
%"TAP"
"1","(-5300,1575)","2","mstr_standard","I4";
;
CDS_LIB"mstr_standard"
BODY_TYPE"PLUMBING"
HDL_TAP"TRUE";
"B \NAC \NWC"3;
"S \NAC"
BN"19"15;
%"TAP"
"1","(-5300,3425)","2","mstr_standard","I40";
;
CDS_LIB"mstr_standard"
BODY_TYPE"PLUMBING"
HDL_TAP"TRUE";
"B \NAC \NWC"4;
"S \NAC"
BN"3"38;
%"TAP"
"1","(-5300,3475)","2","mstr_standard","I41";
;
CDS_LIB"mstr_standard"
BODY_TYPE"PLUMBING"
HDL_TAP"TRUE";
"B \NAC \NWC"4;
"S \NAC"
BN"2"39;
%"TAP"
"1","(-5300,3575)","2","mstr_standard","I42";
;
CDS_LIB"mstr_standard"
BODY_TYPE"PLUMBING"
HDL_TAP"TRUE";
"B \NAC \NWC"4;
"S \NAC"
BN"0"41;
%"TAP"
"1","(-5300,3525)","2","mstr_standard","I43";
;
CDS_LIB"mstr_standard"
BODY_TYPE"PLUMBING"
HDL_TAP"TRUE";
"B \NAC \NWC"4;
"S \NAC"
BN"1"40;
%"TAP"
"1","(-2975,1575)","0","mstr_standard","I44";
;
CDS_LIB"mstr_standard"
BODY_TYPE"PLUMBING"
HDL_TAP"TRUE";
"B \NAC \NWC"1;
"S \NAC"
BN"19"52;
%"TAP"
"1","(-2975,1625)","0","mstr_standard","I45";
;
CDS_LIB"mstr_standard"
BODY_TYPE"PLUMBING"
HDL_TAP"TRUE";
"B \NAC \NWC"1;
"S \NAC"
BN"18"53;
%"TAP"
"1","(-2975,1675)","0","mstr_standard","I46";
;
CDS_LIB"mstr_standard"
BODY_TYPE"PLUMBING"
HDL_TAP"TRUE";
"B \NAC \NWC"1;
"S \NAC"
BN"17"54;
%"TAP"
"1","(-2975,1725)","0","mstr_standard","I47";
;
CDS_LIB"mstr_standard"
BODY_TYPE"PLUMBING"
HDL_TAP"TRUE";
"B \NAC \NWC"1;
"S \NAC"
BN"16"55;
%"TAP"
"1","(-2975,1775)","0","mstr_standard","I48";
;
CDS_LIB"mstr_standard"
BODY_TYPE"PLUMBING"
HDL_TAP"TRUE";
"B \NAC \NWC"1;
"S \NAC"
BN"15"56;
%"TAP"
"1","(-2975,1825)","0","mstr_standard","I49";
;
CDS_LIB"mstr_standard"
BODY_TYPE"PLUMBING"
HDL_TAP"TRUE";
"B \NAC \NWC"1;
"S \NAC"
BN"14"57;
%"TAP"
"1","(-5300,1675)","2","mstr_standard","I5";
;
CDS_LIB"mstr_standard"
BODY_TYPE"PLUMBING"
HDL_TAP"TRUE";
"B \NAC \NWC"3;
"S \NAC"
BN"17"17;
%"TAP"
"1","(-2975,1875)","0","mstr_standard","I50";
;
CDS_LIB"mstr_standard"
BODY_TYPE"PLUMBING"
HDL_TAP"TRUE";
"B \NAC \NWC"1;
"S \NAC"
BN"13"58;
%"TAP"
"1","(-2975,1925)","0","mstr_standard","I51";
;
CDS_LIB"mstr_standard"
BODY_TYPE"PLUMBING"
HDL_TAP"TRUE";
"B \NAC \NWC"1;
"S \NAC"
BN"12"59;
%"TAP"
"1","(-2975,1975)","0","mstr_standard","I52";
;
CDS_LIB"mstr_standard"
BODY_TYPE"PLUMBING"
HDL_TAP"TRUE";
"B \NAC \NWC"1;
"S \NAC"
BN"11"60;
%"TAP"
"1","(-2975,2025)","0","mstr_standard","I53";
;
CDS_LIB"mstr_standard"
BODY_TYPE"PLUMBING"
HDL_TAP"TRUE";
"B \NAC \NWC"1;
"S \NAC"
BN"10"61;
%"TAP"
"1","(-2975,2075)","0","mstr_standard","I54";
;
CDS_LIB"mstr_standard"
BODY_TYPE"PLUMBING"
HDL_TAP"TRUE";
"B \NAC \NWC"1;
"S \NAC"
BN"9"10;
%"TAP"
"1","(-2975,2125)","0","mstr_standard","I55";
;
CDS_LIB"mstr_standard"
BODY_TYPE"PLUMBING"
HDL_TAP"TRUE";
"B \NAC \NWC"1;
"S \NAC"
BN"8"78;
%"TAP"
"1","(-2975,2175)","0","mstr_standard","I56";
;
CDS_LIB"mstr_standard"
BODY_TYPE"PLUMBING"
HDL_TAP"TRUE";
"B \NAC \NWC"1;
"S \NAC"
BN"7"79;
%"TAP"
"1","(-2975,2225)","0","mstr_standard","I57";
;
CDS_LIB"mstr_standard"
BODY_TYPE"PLUMBING"
HDL_TAP"TRUE";
"B \NAC \NWC"1;
"S \NAC"
BN"6"11;
%"TAP"
"1","(-2975,2275)","0","mstr_standard","I58";
;
CDS_LIB"mstr_standard"
BODY_TYPE"PLUMBING"
HDL_TAP"TRUE";
"B \NAC \NWC"1;
"S \NAC"
BN"5"80;
%"TAP"
"1","(-2975,2325)","0","mstr_standard","I59";
;
CDS_LIB"mstr_standard"
BODY_TYPE"PLUMBING"
HDL_TAP"TRUE";
"B \NAC \NWC"1;
"S \NAC"
BN"4"12;
%"TAP"
"1","(-5300,1725)","2","mstr_standard","I6";
;
CDS_LIB"mstr_standard"
BODY_TYPE"PLUMBING"
HDL_TAP"TRUE";
"B \NAC \NWC"3;
"S \NAC"
BN"16"18;
%"TAP"
"1","(-2975,2375)","0","mstr_standard","I60";
;
CDS_LIB"mstr_standard"
BODY_TYPE"PLUMBING"
HDL_TAP"TRUE";
"B \NAC \NWC"1;
"S \NAC"
BN"3"81;
%"TAP"
"1","(-2975,2425)","0","mstr_standard","I61";
;
CDS_LIB"mstr_standard"
BODY_TYPE"PLUMBING"
HDL_TAP"TRUE";
"B \NAC \NWC"1;
"S \NAC"
BN"2"82;
%"TAP"
"1","(-2975,2475)","0","mstr_standard","I62";
;
CDS_LIB"mstr_standard"
BODY_TYPE"PLUMBING"
HDL_TAP"TRUE";
"B \NAC \NWC"1;
"S \NAC"
BN"1"83;
%"TAP"
"1","(-2975,2525)","0","mstr_standard","I63";
;
CDS_LIB"mstr_standard"
BODY_TYPE"PLUMBING"
HDL_TAP"TRUE";
"B \NAC \NWC"1;
"S \NAC"
BN"0"84;
%"TAP"
"1","(-2975,2625)","0","mstr_standard","I64";
;
CDS_LIB"mstr_standard"
BODY_TYPE"PLUMBING"
HDL_TAP"TRUE";
"B \NAC \NWC"2;
"S \NAC"
BN"19"62;
%"TAP"
"1","(-2975,2675)","0","mstr_standard","I65";
;
CDS_LIB"mstr_standard"
BODY_TYPE"PLUMBING"
HDL_TAP"TRUE";
"B \NAC \NWC"2;
"S \NAC"
BN"18"63;
%"TAP"
"1","(-2975,2725)","0","mstr_standard","I66";
;
CDS_LIB"mstr_standard"
BODY_TYPE"PLUMBING"
HDL_TAP"TRUE";
"B \NAC \NWC"2;
"S \NAC"
BN"17"64;
%"TAP"
"1","(-2975,2775)","0","mstr_standard","I67";
;
CDS_LIB"mstr_standard"
BODY_TYPE"PLUMBING"
HDL_TAP"TRUE";
"B \NAC \NWC"2;
"S \NAC"
BN"16"65;
%"TAP"
"1","(-2975,2825)","0","mstr_standard","I68";
;
CDS_LIB"mstr_standard"
BODY_TYPE"PLUMBING"
HDL_TAP"TRUE";
"B \NAC \NWC"2;
"S \NAC"
BN"15"66;
%"TAP"
"1","(-2975,2875)","0","mstr_standard","I69";
;
CDS_LIB"mstr_standard"
BODY_TYPE"PLUMBING"
HDL_TAP"TRUE";
"B \NAC \NWC"2;
"S \NAC"
BN"14"67;
%"TAP"
"1","(-5300,1775)","2","mstr_standard","I7";
;
CDS_LIB"mstr_standard"
BODY_TYPE"PLUMBING"
HDL_TAP"TRUE";
"B \NAC \NWC"3;
"S \NAC"
BN"15"19;
%"TAP"
"1","(-2975,2925)","0","mstr_standard","I70";
;
CDS_LIB"mstr_standard"
BODY_TYPE"PLUMBING"
HDL_TAP"TRUE";
"B \NAC \NWC"2;
"S \NAC"
BN"13"68;
%"TAP"
"1","(-2975,2975)","0","mstr_standard","I71";
;
CDS_LIB"mstr_standard"
BODY_TYPE"PLUMBING"
HDL_TAP"TRUE";
"B \NAC \NWC"2;
"S \NAC"
BN"12"9;
%"TAP"
"1","(-2975,3025)","0","mstr_standard","I72";
;
CDS_LIB"mstr_standard"
BODY_TYPE"PLUMBING"
HDL_TAP"TRUE";
"B \NAC \NWC"2;
"S \NAC"
BN"11"7;
%"TAP"
"1","(-2975,3075)","0","mstr_standard","I73";
;
CDS_LIB"mstr_standard"
BODY_TYPE"PLUMBING"
HDL_TAP"TRUE";
"B \NAC \NWC"2;
"S \NAC"
BN"10"69;
%"TAP"
"1","(-2975,3125)","0","mstr_standard","I74";
;
CDS_LIB"mstr_standard"
BODY_TYPE"PLUMBING"
HDL_TAP"TRUE";
"B \NAC \NWC"2;
"S \NAC"
BN"9"8;
%"TAP"
"1","(-2975,3225)","0","mstr_standard","I75";
;
CDS_LIB"mstr_standard"
BODY_TYPE"PLUMBING"
HDL_TAP"TRUE";
"B \NAC \NWC"2;
"S \NAC"
BN"7"71;
%"TAP"
"1","(-2975,3175)","0","mstr_standard","I76";
;
CDS_LIB"mstr_standard"
BODY_TYPE"PLUMBING"
HDL_TAP"TRUE";
"B \NAC \NWC"2;
"S \NAC"
BN"8"70;
%"TAP"
"1","(-2975,3275)","0","mstr_standard","I77";
;
CDS_LIB"mstr_standard"
BODY_TYPE"PLUMBING"
HDL_TAP"TRUE";
"B \NAC \NWC"2;
"S \NAC"
BN"6"72;
%"TAP"
"1","(-2975,3325)","0","mstr_standard","I78";
;
CDS_LIB"mstr_standard"
BODY_TYPE"PLUMBING"
HDL_TAP"TRUE";
"B \NAC \NWC"2;
"S \NAC"
BN"5"73;
%"TAP"
"1","(-2975,3375)","0","mstr_standard","I79";
;
CDS_LIB"mstr_standard"
BODY_TYPE"PLUMBING"
HDL_TAP"TRUE";
"B \NAC \NWC"2;
"S \NAC"
BN"4"74;
%"TAP"
"1","(-2975,3475)","0","mstr_standard","I80";
;
CDS_LIB"mstr_standard"
BODY_TYPE"PLUMBING"
HDL_TAP"TRUE";
"B \NAC \NWC"2;
"S \NAC"
BN"2"75;
%"TAP"
"1","(-2975,3425)","0","mstr_standard","I81";
;
CDS_LIB"mstr_standard"
BODY_TYPE"PLUMBING"
HDL_TAP"TRUE";
"B \NAC \NWC"2;
"S \NAC"
BN"3"13;
%"TAP"
"1","(-2975,3525)","0","mstr_standard","I82";
;
CDS_LIB"mstr_standard"
BODY_TYPE"PLUMBING"
HDL_TAP"TRUE";
"B \NAC \NWC"2;
"S \NAC"
BN"1"76;
%"TAP"
"1","(-2975,3575)","0","mstr_standard","I83";
;
CDS_LIB"mstr_standard"
BODY_TYPE"PLUMBING"
HDL_TAP"TRUE";
"B \NAC \NWC"2;
"S \NAC"
BN"0"77;
%"SKX_EXT_B"
"14","(-4100,2575)","0","chpset_lib","I86";
;
CDS_SEC"14"
LOCATION"U5D1"
PART_NUMBER"TBD"
MATERIAL"IC"
PACK_TYPE"BGA1"
CDS_LIB"chpset_lib"
SEC_TYPE"BGA1"
SEC"14"
CDS_LOCATION"U5D1"
ROOM"CPU0";
"UPI1_TX_DP<0>"
$PN"P3"62;
"UPI1_TX_DP<1>"
$PN"K3"63;
"UPI1_TX_DP<2>"
$PN"M5"64;
"UPI1_TX_DP<3>"
$PN"H5"65;
"UPI1_TX_DP<4>"
$PN"F7"66;
"UPI1_TX_DP<5>"
$PN"K7"67;
"UPI1_TX_DP<6>"
$PN"J8"68;
"UPI1_TX_DP<7>"
$PN"F9"9;
"UPI1_TX_DP<8>"
$PN"E10"7;
"UPI1_TX_DP<9>"
$PN"H9"69;
"UPI1_TX_DP<10>"
$PN"G12"8;
"UPI1_TX_DP<11>"
$PN"F13"70;
"UPI1_TX_DP<12>"
$PN"E14"71;
"UPI1_TX_DP<13>"
$PN"H15"72;
"UPI1_TX_DP<14>"
$PN"G16"73;
"UPI1_TX_DP<15>"
$PN"L18"74;
"UPI1_TX_DP<16>"
$PN"J18"13;
"UPI1_TX_DP<17>"
$PN"H19"75;
"UPI1_TX_DP<18>"
$PN"G20"76;
"UPI1_TX_DP<19>"
$PN"K21"77;
"UPI1_TX_DN<0>"
$PN"M3"52;
"UPI1_TX_DN<1>"
$PN"L4"53;
"UPI1_TX_DN<2>"
$PN"K5"54;
"UPI1_TX_DN<3>"
$PN"J6"55;
"UPI1_TX_DN<4>"
$PN"G6"56;
"UPI1_TX_DN<5>"
$PN"H7"57;
"UPI1_TX_DN<6>"
$PN"K9"58;
"UPI1_TX_DN<7>"
$PN"D9"59;
"UPI1_TX_DN<8>"
$PN"F11"60;
"UPI1_TX_DN<9>"
$PN"G10"61;
"UPI1_TX_DN<10>"
$PN"E12"10;
"UPI1_TX_DN<11>"
$PN"G14"78;
"UPI1_TX_DN<12>"
$PN"D15"79;
"UPI1_TX_DN<13>"
$PN"F15"11;
"UPI1_TX_DN<14>"
$PN"H17"80;
"UPI1_TX_DN<15>"
$PN"K19"12;
"UPI1_TX_DN<16>"
$PN"G18"81;
"UPI1_TX_DN<17>"
$PN"J20"82;
"UPI1_TX_DN<18>"
$PN"F21"83;
"UPI1_TX_DN<19>"
$PN"H21"84;
"UPI1_RX_DP<0>"
$PN"R6"25;
"UPI1_RX_DP<1>"
$PN"T7"26;
"UPI1_RX_DP<2>"
$PN"U8"27;
"UPI1_RX_DP<3>"
$PN"R8"28;
"UPI1_RX_DP<4>"
$PN"N10"29;
"UPI1_RX_DP<5>"
$PN"U10"30;
"UPI1_RX_DP<6>"
$PN"T11"5;
"UPI1_RX_DP<7>"
$PN"N12"14;
"UPI1_RX_DP<8>"
$PN"M13"6;
"UPI1_RX_DP<9>"
$PN"P13"31;
"UPI1_RX_DP<10>"
$PN"T15"32;
"UPI1_RX_DP<11>"
$PN"N16"33;
"UPI1_RX_DP<12>"
$PN"W16"34;
"UPI1_RX_DP<13>"
$PN"V17"35;
"UPI1_RX_DP<14>"
$PN"P19"36;
"UPI1_RX_DP<15>"
$PN"T19"37;
"UPI1_RX_DP<16>"
$PN"T21"38;
"UPI1_RX_DP<17>"
$PN"Y19"39;
"UPI1_RX_DP<18>"
$PN"W20"40;
"UPI1_RX_DP<19>"
$PN"AA20"41;
"UPI1_RX_DN<0>"
$PN"T5"15;
"UPI1_RX_DN<1>"
$PN"P7"16;
"UPI1_RX_DN<2>"
$PN"V7"17;
"UPI1_RX_DN<3>"
$PN"T9"18;
"UPI1_RX_DN<4>"
$PN"P9"19;
"UPI1_RX_DN<5>"
$PN"R10"20;
"UPI1_RX_DN<6>"
$PN"U12"21;
"UPI1_RX_DN<7>"
$PN"L12"22;
"UPI1_RX_DN<8>"
$PN"N14"23;
"UPI1_RX_DN<9>"
$PN"R12"24;
"UPI1_RX_DN<10>"
$PN"R16"42;
"UPI1_RX_DN<11>"
$PN"P17"43;
"UPI1_RX_DN<12>"
$PN"U16"44;
"UPI1_RX_DN<13>"
$PN"W18"45;
"UPI1_RX_DN<14>"
$PN"R20"46;
"UPI1_RX_DN<15>"
$PN"U18"47;
"UPI1_RX_DN<16>"
$PN"P21"48;
"UPI1_RX_DN<17>"
$PN"V19"49;
"UPI1_RX_DN<18>"
$PN"Y21"50;
"UPI1_RX_DN<19>"
$PN"AB19"51;
%"TAP"
"1","(-5300,1875)","2","mstr_standard","I9";
;
CDS_LIB"mstr_standard"
BODY_TYPE"PLUMBING"
HDL_TAP"TRUE";
"B \NAC \NWC"3;
"S \NAC"
BN"13"21;
END.
